# T6G (Grand Teton) — schematic netlist excerpt (pin names and nets, part order shuffled) for the footprints in the layout excerpt that follows; sources: Cadence DE-HDL packaged netlist, KiCad conversion of 04192023_DAF0TMB3IC0_F0TG_MB_C_brd_V02_OCP.brd

R8058  Q_RES  0 5% CHIP  pkg 0402LF  page 200 : A = FM_PVDDCR_CPU1_P0_EN ; B = PVDDCR_CPU1_P0_EN_R
R519  Q_RES  2.2K 5% EMPTY  pkg 0402LF  page 54 : A = CPU1_SA0 ; B = GND
C783  Q_CAP  1UF 4V 20% X6S  pkg 0201  page 301 : A = P0V9_CPU0_RT2_2A ; B = GND

(kicad_pcb
	(version 20260206)
	(generator "pcbnew")
	(generator_version "10.0")
	(general
		(thickness 1.6)
		(legacy_teardrops no)
	)
	(paper "A4")
	(title_block
		(title "04192023_DAF0TMB3IC0_F0TG_MB_C_brd_V02_OCP.brd")
		(comment 1 "Grand Teton / footprints 8122-8124 of 8354")
	)
	(layers
		(0 "F.Cu" signal "TOP")
		(4 "In1.Cu" signal "GND")
		(6 "In2.Cu" signal "IN1")
		(8 "In3.Cu" signal "GND1")
		(10 "In4.Cu" signal "IN2")
		(12 "In5.Cu" signal "GND2")
		(14 "In6.Cu" signal "IN3")
		(16 "In7.Cu" signal "GND3")
		(18 "In8.Cu" signal "VCC")
		(20 "In9.Cu" signal "VCC1")
		(22 "In10.Cu" signal "GND4")
		(24 "In11.Cu" signal "IN4")
		(26 "In12.Cu" signal "GND5")
		(28 "In13.Cu" signal "IN5")
		(30 "In14.Cu" signal "GND6")
		(32 "In15.Cu" signal "IN6")
		(34 "In16.Cu" signal "GND7")
		(2 "B.Cu" signal "BOTTOM")
		(9 "F.Adhes" user "F.Adhesive")
		(11 "B.Adhes" user "B.Adhesive")
		(13 "F.Paste" user "Package Geometry/Pastemask Top")
		(15 "B.Paste" user "Package Geometry/Pastemask Bottom")
		(5 "F.SilkS" user "Ref Des/Silkscreen Top")
		(7 "B.SilkS" user "Ref Des/Silkscreen Bottom")
		(1 "F.Mask" user "Board Geometry/Soldermask Top")
		(3 "B.Mask" user "Board Geometry/Soldermask Bottom")
		(17 "Dwgs.User" user "User.Drawings")
		(19 "Cmts.User" user "User.Comments")
		(21 "Eco1.User" user "User.Eco1")
		(23 "Eco2.User" user "User.Eco2")
		(25 "Edge.Cuts" user "Board Geometry/Outline")
		(27 "Margin" user)
		(31 "F.CrtYd" user "Package Geometry/Place Bound Top")
		(29 "B.CrtYd" user "Package Geometry/Place Bound Bottom")
		(35 "F.Fab" user "Ref Des/Assembly Top")
		(33 "B.Fab" user "Ref Des/Assembly Bottom")
	)
	(footprint ""
		(layer "B.Cu")
		(at 91.493594 -303.255172 180)
		(property "Reference" "R519"
			(at 0 0 0)
			(layer "B.SilkS")
			(hide yes)
			(effects
				(font
					(size 1.27 1.27)
				)
				(justify mirror)
			)
		)
		(property "Value" ""
			(at 0 0 0)
			(layer "B.Fab")
			(effects
				(font
					(size 1.27 1.27)
				)
				(justify mirror)
			)
		)
		(duplicate_pad_numbers_are_jumpers no)
		(fp_line
			(start 0.7874 0.4064)
			(end 0.7874 -0.4064)
			(stroke
				(width 0.1524)
				(type default)
			)
			(layer "B.SilkS")
		)
		(fp_line
			(start 0.7874 -0.4064)
			(end -0.7874 -0.4064)
			(stroke
				(width 0.1524)
				(type default)
			)
			(layer "B.SilkS")
		)
		(fp_line
			(start -0.7874 0.4064)
			(end 0.7874 0.4064)
			(stroke
				(width 0.1524)
				(type default)
			)
			(layer "B.SilkS")
		)
		(fp_line
			(start -0.7874 -0.4064)
			(end -0.7874 0.4064)
			(stroke
				(width 0.1524)
				(type default)
			)
			(layer "B.SilkS")
		)
		(fp_line
			(start 0.67945 0.3048)
			(end 0.67945 -0.305054)
			(stroke
				(width 0.1)
				(type default)
			)
			(layer "B.Fab")
		)
		(fp_line
			(start 0.67945 -0.305054)
			(end 0.12065 -0.305054)
			(stroke
				(width 0.1)
				(type default)
			)
			(layer "B.Fab")
		)
		(fp_line
			(start 0.12065 0.3048)
			(end 0.67945 0.3048)
			(stroke
				(width 0.1)
				(type default)
			)
			(layer "B.Fab")
		)
		(fp_line
			(start 0.12065 0.2794)
			(end 0.12065 0.3048)
			(stroke
				(width 0.1)
				(type default)
			)
			(layer "B.Fab")
		)
		(fp_line
			(start 0.12065 -0.2794)
			(end -0.12065 -0.2794)
			(stroke
				(width 0.1)
				(type default)
			)
			(layer "B.Fab")
		)
		(fp_line
			(start 0.12065 -0.305054)
			(end 0.12065 -0.2794)
			(stroke
				(width 0.1)
				(type default)
			)
			(layer "B.Fab")
		)
		(fp_line
			(start -0.120396 0.3048)
			(end -0.120396 0.2794)
			(stroke
				(width 0.1)
				(type default)
			)
			(layer "B.Fab")
		)
		(fp_line
			(start -0.120396 0.2794)
			(end 0.12065 0.2794)
			(stroke
				(width 0.1)
				(type default)
			)
			(layer "B.Fab")
		)
		(fp_line
			(start -0.12065 -0.2794)
			(end -0.12065 -0.3048)
			(stroke
				(width 0.1)
				(type default)
			)
			(layer "B.Fab")
		)
		(fp_line
			(start -0.12065 -0.3048)
			(end -0.67945 -0.3048)
			(stroke
				(width 0.1)
				(type default)
			)
			(layer "B.Fab")
		)
		(fp_line
			(start -0.67945 0.3048)
			(end -0.120396 0.3048)
			(stroke
				(width 0.1)
				(type default)
			)
			(layer "B.Fab")
		)
		(fp_line
			(start -0.67945 -0.3048)
			(end -0.67945 0.3048)
			(stroke
				(width 0.1)
				(type default)
			)
			(layer "B.Fab")
		)
		(pad "1" smd circle
			(at 0.40005 0)
			(size 0 0)
			(layers "B.Cu" "B.Mask" "B.Paste")
			(net "CPU1_SA0")
		)
		(pad "2" smd circle
			(at -0.40005 0)
			(size 0 0)
			(layers "B.Cu" "B.Mask" "B.Paste")
			(net "GND")
		)
	)
	(footprint ""
		(layer "B.Cu")
		(at 406.606248 -395.148562 90)
		(property "Reference" "C783"
			(at 0 0 90)
			(layer "B.SilkS")
			(hide yes)
			(effects
				(font
					(size 1.27 1.27)
				)
				(justify mirror)
			)
		)
		(property "Value" ""
			(at 0 0 90)
			(layer "B.Fab")
			(effects
				(font
					(size 1.27 1.27)
				)
				(justify mirror)
			)
		)
		(duplicate_pad_numbers_are_jumpers no)
		(fp_line
			(start 0.299974 -0.150114)
			(end -0.299974 -0.150114)
			(stroke
				(width 0.1)
				(type default)
			)
			(layer "B.Fab")
		)
		(fp_line
			(start -0.299974 -0.150114)
			(end -0.299974 0.150114)
			(stroke
				(width 0.1)
				(type default)
			)
			(layer "B.Fab")
		)
		(fp_line
			(start 0.299974 0.150114)
			(end 0.299974 -0.150114)
			(stroke
				(width 0.1)
				(type default)
			)
			(layer "B.Fab")
		)
		(fp_line
			(start -0.299974 0.150114)
			(end 0.299974 0.150114)
			(stroke
				(width 0.1)
				(type default)
			)
			(layer "B.Fab")
		)
		(pad "1" smd rect
			(at 0.2667 0 270)
			(size 0.3048 0.381)
			(layers "B.Cu" "B.Mask" "B.Paste")
			(net "P0V9_CPU0_RT2_2A")
		)
		(pad "2" smd rect
			(at -0.2667 0 270)
			(size 0.3048 0.381)
			(layers "B.Cu" "B.Mask" "B.Paste")
			(net "GND")
		)
	)
	(footprint ""
		(layer "B.Cu")
		(at 304.419 -361.696 180)
		(property "Reference" "R8058"
			(at 0 0 0)
			(layer "B.SilkS")
			(hide yes)
			(effects
				(font
					(size 1.27 1.27)
				)
				(justify mirror)
			)
		)
		(property "Value" ""
			(at 0 0 0)
			(layer "B.Fab")
			(effects
				(font
					(size 1.27 1.27)
				)
				(justify mirror)
			)
		)
		(duplicate_pad_numbers_are_jumpers no)
		(fp_line
			(start 0.7874 0.4064)
			(end 0.7874 -0.4064)
			(stroke
				(width 0.1524)
				(type default)
			)
			(layer "B.SilkS")
		)
		(fp_line
			(start 0.7874 -0.4064)
			(end -0.7874 -0.4064)
			(stroke
				(width 0.1524)
				(type default)
			)
			(layer "B.SilkS")
		)
		(fp_line
			(start -0.7874 0.4064)
			(end 0.7874 0.4064)
			(stroke
				(width 0.1524)
				(type default)
			)
			(layer "B.SilkS")
		)
		(fp_line
			(start -0.7874 -0.4064)
			(end -0.7874 0.4064)
			(stroke
				(width 0.1524)
				(type default)
			)
			(layer "B.SilkS")
		)
		(fp_line
			(start 0.67945 0.3048)
			(end 0.67945 -0.305054)
			(stroke
				(width 0.1)
				(type default)
			)
			(layer "B.Fab")
		)
		(fp_line
			(start 0.67945 -0.305054)
			(end 0.12065 -0.305054)
			(stroke
				(width 0.1)
				(type default)
			)
			(layer "B.Fab")
		)
		(fp_line
			(start 0.12065 0.3048)
			(end 0.67945 0.3048)
			(stroke
				(width 0.1)
				(type default)
			)
			(layer "B.Fab")
		)
		(fp_line
			(start 0.12065 0.2794)
			(end 0.12065 0.3048)
			(stroke
				(width 0.1)
				(type default)
			)
			(layer "B.Fab")
		)
		(fp_line
			(start 0.12065 -0.2794)
			(end -0.12065 -0.2794)
			(stroke
				(width 0.1)
				(type default)
			)
			(layer "B.Fab")
		)
		(fp_line
			(start 0.12065 -0.305054)
			(end 0.12065 -0.2794)
			(stroke
				(width 0.1)
				(type default)
			)
			(layer "B.Fab")
		)
		(fp_line
			(start -0.120396 0.3048)
			(end -0.120396 0.2794)
			(stroke
				(width 0.1)
				(type default)
			)
			(layer "B.Fab")
		)
		(fp_line
			(start -0.120396 0.2794)
			(end 0.12065 0.2794)
			(stroke
				(width 0.1)
				(type default)
			)
			(layer "B.Fab")
		)
		(fp_line
			(start -0.12065 -0.2794)
			(end -0.12065 -0.3048)
			(stroke
				(width 0.1)
				(type default)
			)
			(layer "B.Fab")
		)
		(fp_line
			(start -0.12065 -0.3048)
			(end -0.67945 -0.3048)
			(stroke
				(width 0.1)
				(type default)
			)
			(layer "B.Fab")
		)
		(fp_line
			(start -0.67945 0.3048)
			(end -0.120396 0.3048)
			(stroke
				(width 0.1)
				(type default)
			)
			(layer "B.Fab")
		)
		(fp_line
			(start -0.67945 -0.3048)
			(end -0.67945 0.3048)
			(stroke
				(width 0.1)
				(type default)
			)
			(layer "B.Fab")
		)
		(pad "1" smd circle
			(at 0.40005 0)
			(size 0 0)
			(layers "B.Cu" "B.Mask" "B.Paste")
			(net "FM_PVDDCR_CPU1_P0_EN")
		)
		(pad "2" smd circle
			(at -0.40005 0)
			(size 0 0)
			(layers "B.Cu" "B.Mask" "B.Paste")
			(net "PVDDCR_CPU1_P0_EN_R")
		)
	)
)
